# BASEBOARD_FAB2 (Tioga Pass) — schematic netlist excerpt (pin names and nets, part order shuffled) for the footprints in the layout excerpt that follows; sources: Cadence DE-HDL packaged netlist, KiCad conversion of Wiwynn_Tioga_Pass_MB.brd

C6P9  CAP_A  0.1UF 16V 10% X7R  pkg 0402V  page 102 : A = P3V3_DB1200 ; B = GND
C7P14  CAP  100UF 4V 20% X5R  pkg 0805  page 76 : A = PVCCMCP_CPU1 ; B = GND
C5U12  CAP  100UF 4V 20% X5R  pkg 0805  page 221 : A = PVTT_ABC ; B = GND

(kicad_pcb
	(version 20260206)
	(generator "pcbnew")
	(generator_version "10.0")
	(general
		(thickness 1.6)
		(legacy_teardrops no)
	)
	(paper "A4")
	(title_block
		(title "Wiwynn_Tioga_Pass_MB.brd")
		(comment 1 "Tioga Pass / footprints 4215-4217 of 4770")
	)
	(layers
		(0 "F.Cu" signal "TOP")
		(4 "In1.Cu" signal "L2GND")
		(6 "In2.Cu" signal "L3")
		(8 "In3.Cu" signal "L4GND")
		(10 "In4.Cu" signal "L5")
		(12 "In5.Cu" signal "L6GND")
		(14 "In6.Cu" signal "L7VCC")
		(16 "In7.Cu" signal "L8VCC")
		(18 "In8.Cu" signal "L9GND")
		(20 "In9.Cu" signal "L10")
		(22 "In10.Cu" signal "L11GND")
		(24 "In11.Cu" signal "L12")
		(26 "In12.Cu" signal "L13GND")
		(2 "B.Cu" signal "BOTTOM")
		(9 "F.Adhes" user "F.Adhesive")
		(11 "B.Adhes" user "B.Adhesive")
		(13 "F.Paste" user "Package Geometry/Pastemask Top")
		(15 "B.Paste" user "Package Geometry/Pastemask Bottom")
		(5 "F.SilkS" user "Ref Des/Silkscreen Top")
		(7 "B.SilkS" user "Ref Des/Silkscreen Bottom")
		(1 "F.Mask" user "Board Geometry/Soldermask Top")
		(3 "B.Mask" user "Board Geometry/Soldermask Bottom")
		(17 "Dwgs.User" user "User.Drawings")
		(19 "Cmts.User" user "User.Comments")
		(21 "Eco1.User" user "User.Eco1")
		(23 "Eco2.User" user "User.Eco2")
		(25 "Edge.Cuts" user "Board Geometry/Outline")
		(27 "Margin" user)
		(31 "F.CrtYd" user "Package Geometry/Place Bound Top")
		(29 "B.CrtYd" user "Package Geometry/Place Bound Bottom")
		(35 "F.Fab" user "Ref Des/Assembly Top")
		(33 "B.Fab" user "Ref Des/Assembly Bottom")
	)
	(footprint ""
		(layer "B.Cu")
		(at 261.9248 -26.543 90)
		(property "Reference" "C5U12"
			(at -1.47828 0.78994 180)
			(unlocked yes)
			(layer "B.SilkS")
			(effects
				(font
					(size 0.4064 0.254)
					(thickness 0.1524)
				)
				(justify mirror)
			)
		)
		(property "Value" ""
			(at 0 0 90)
			(layer "B.Fab")
			(effects
				(font
					(size 1.27 1.27)
				)
				(justify mirror)
			)
		)
		(duplicate_pad_numbers_are_jumpers no)
		(fp_poly
			(pts
				(xy 0.7239 -0.2159) (xy -0.7239 -0.2159) (xy -0.7239 1.9939) (xy 0.7239 1.9939)
			)
			(stroke
				(width 0)
				(type default)
			)
			(fill no)
			(layer "B.CrtYd")
		)
		(fp_line
			(start 0.7239 -0.2159)
			(end 0.7239 1.9939)
			(stroke
				(width 0.1)
				(type default)
			)
			(layer "B.Fab")
		)
		(fp_line
			(start -0.7239 -0.2159)
			(end 0.7239 -0.2159)
			(stroke
				(width 0.1)
				(type default)
			)
			(layer "B.Fab")
		)
		(fp_line
			(start 0.7239 1.9939)
			(end -0.7239 1.9939)
			(stroke
				(width 0.1)
				(type default)
			)
			(layer "B.Fab")
		)
		(fp_line
			(start -0.7239 1.9939)
			(end -0.7239 -0.2159)
			(stroke
				(width 0.1)
				(type default)
			)
			(layer "B.Fab")
		)
		(pad "1" smd rect
			(at 0 0 270)
			(size 1.27 1.016)
			(layers "B.Cu" "B.Mask" "B.Paste")
			(net "PVTT_ABC")
		)
		(pad "2" smd rect
			(at 0 1.778 270)
			(size 1.27 1.016)
			(layers "B.Cu" "B.Mask" "B.Paste")
			(net "GND")
		)
		(zone
			(layer "B.Cu")
			(hatch none 0.5)
			(connect_pads
				(clearance 0)
			)
			(min_thickness 0.25)
			(keepout
				(tracks not_allowed)
				(vias allowed)
				(pads allowed)
				(copperpour not_allowed)
				(footprints allowed)
			)
			(placement
				(enabled no)
				(sheetname "")
			)
			(fill
				(thermal_gap 0.5)
				(thermal_bridge_width 0.5)
				(island_removal_mode 0)
			)
			(polygon
				(pts
					(xy 262.4328 -27.178) (xy 262.4328 -25.908) (xy 263.1948 -25.908) (xy 263.1948 -27.178)
				)
			)
		)
	)
	(footprint ""
		(layer "B.Cu")
		(at 173.863 -81.661 -90)
		(property "Reference" "C6P9"
			(at 0 0 90)
			(layer "B.SilkS")
			(hide yes)
			(effects
				(font
					(size 1.27 1.27)
				)
				(justify mirror)
			)
		)
		(property "Value" ""
			(at 0 0 90)
			(layer "B.Fab")
			(effects
				(font
					(size 1.27 1.27)
				)
				(justify mirror)
			)
		)
		(duplicate_pad_numbers_are_jumpers no)
		(fp_poly
			(pts
				(xy -0.3048 -0.1016) (xy -0.3048 0.9906) (xy 0.3048 0.9906) (xy 0.3048 -0.1016)
			)
			(stroke
				(width 0)
				(type default)
			)
			(fill no)
			(layer "B.CrtYd")
		)
		(fp_line
			(start -0.3048 0.9906)
			(end -0.3048 -0.1016)
			(stroke
				(width 0.1)
				(type default)
			)
			(layer "B.Fab")
		)
		(fp_line
			(start 0.3048 0.9906)
			(end -0.3048 0.9906)
			(stroke
				(width 0.1)
				(type default)
			)
			(layer "B.Fab")
		)
		(fp_line
			(start -0.3048 -0.1016)
			(end 0.3048 -0.1016)
			(stroke
				(width 0.1)
				(type default)
			)
			(layer "B.Fab")
		)
		(fp_line
			(start 0.3048 -0.1016)
			(end 0.3048 0.9906)
			(stroke
				(width 0.1)
				(type default)
			)
			(layer "B.Fab")
		)
		(pad "1" smd rect
			(at 0 0 90)
			(size 0.508 0.508)
			(layers "B.Cu" "B.Mask" "B.Paste")
			(net "P3V3_DB1200")
		)
		(pad "2" smd rect
			(at 0 0.889 90)
			(size 0.508 0.508)
			(layers "B.Cu" "B.Mask" "B.Paste")
			(net "GND")
		)
		(zone
			(layer "B.Cu")
			(hatch none 0.5)
			(connect_pads
				(clearance 0)
			)
			(min_thickness 0.25)
			(keepout
				(tracks not_allowed)
				(vias allowed)
				(pads allowed)
				(copperpour not_allowed)
				(footprints allowed)
			)
			(placement
				(enabled no)
				(sheetname "")
			)
			(fill
				(thermal_gap 0.5)
				(thermal_bridge_width 0.5)
				(island_removal_mode 0)
			)
			(polygon
				(pts
					(xy 173.228 -81.407) (xy 173.228 -81.915) (xy 173.609 -81.915) (xy 173.609 -81.407)
				)
			)
		)
		(zone
			(layer "B.Cu")
			(hatch none 0.5)
			(connect_pads
				(clearance 0)
			)
			(min_thickness 0.25)
			(keepout
				(tracks allowed)
				(vias not_allowed)
				(pads allowed)
				(copperpour not_allowed)
				(footprints allowed)
			)
			(placement
				(enabled no)
				(sheetname "")
			)
			(fill
				(thermal_gap 0.5)
				(thermal_bridge_width 0.5)
				(island_removal_mode 0)
			)
			(polygon
				(pts
					(xy 173.609 -81.407) (xy 173.609 -81.915) (xy 173.228 -81.915) (xy 173.228 -81.407)
				)
			)
		)
	)
	(footprint ""
		(layer "B.Cu")
		(at 110.007654 -73.51014)
		(property "Reference" "C7P14"
			(at 0 0 0)
			(layer "B.SilkS")
			(hide yes)
			(effects
				(font
					(size 1.27 1.27)
				)
				(justify mirror)
			)
		)
		(property "Value" ""
			(at 0 0 0)
			(layer "B.Fab")
			(effects
				(font
					(size 1.27 1.27)
				)
				(justify mirror)
			)
		)
		(duplicate_pad_numbers_are_jumpers no)
		(fp_poly
			(pts
				(xy 0.7239 -0.2159) (xy -0.7239 -0.2159) (xy -0.7239 1.9939) (xy 0.7239 1.9939)
			)
			(stroke
				(width 0)
				(type default)
			)
			(fill no)
			(layer "B.CrtYd")
		)
		(fp_line
			(start -0.7239 -0.2159)
			(end 0.7239 -0.2159)
			(stroke
				(width 0.1)
				(type default)
			)
			(layer "B.Fab")
		)
		(fp_line
			(start -0.7239 1.9939)
			(end -0.7239 -0.2159)
			(stroke
				(width 0.1)
				(type default)
			)
			(layer "B.Fab")
		)
		(fp_line
			(start 0.7239 -0.2159)
			(end 0.7239 1.9939)
			(stroke
				(width 0.1)
				(type default)
			)
			(layer "B.Fab")
		)
		(fp_line
			(start 0.7239 1.9939)
			(end -0.7239 1.9939)
			(stroke
				(width 0.1)
				(type default)
			)
			(layer "B.Fab")
		)
		(pad "1" smd rect
			(at 0 0 180)
			(size 1.27 1.016)
			(layers "B.Cu" "B.Mask" "B.Paste")
			(net "PVCCMCP_CPU1")
		)
		(pad "2" smd rect
			(at 0 1.778 180)
			(size 1.27 1.016)
			(layers "B.Cu" "B.Mask" "B.Paste")
			(net "GND")
		)
		(zone
			(layer "B.Cu")
			(hatch none 0.5)
			(connect_pads
				(clearance 0)
			)
			(min_thickness 0.25)
			(keepout
				(tracks not_allowed)
				(vias allowed)
				(pads allowed)
				(copperpour not_allowed)
				(footprints allowed)
			)
			(placement
				(enabled no)
				(sheetname "")
			)
			(fill
				(thermal_gap 0.5)
				(thermal_bridge_width 0.5)
				(island_removal_mode 0)
			)
			(polygon
				(pts
					(xy 110.642654 -73.00214) (xy 109.372654 -73.00214) (xy 109.372654 -72.24014) (xy 110.642654 -72.24014)
				)
			)
		)
	)
)
